(kicad_pcb
	(version 20260206)
	(generator "pcbnew")
	(generator_version "10.0")
	(general
		(thickness 1.6)
		(legacy_teardrops no)
	)
	(paper "A4")
	(title_block
		(title "01162023_DA0F0TEBIF0_F0T_Expander_BD_F_brd_V02_OCP.brd")
		(comment 1 "Grand Teton / footprints 1904-1906 of 9728")
	)
	(layers
		(0 "F.Cu" signal "TOP")
		(4 "In1.Cu" signal "GND")
		(6 "In2.Cu" signal "VCC")
		(8 "In3.Cu" signal "VCC1")
		(10 "In4.Cu" signal "GND1")
		(12 "In5.Cu" signal "IN1")
		(14 "In6.Cu" signal "GND2")
		(16 "In7.Cu" signal "IN2")
		(18 "In8.Cu" signal "GND3")
		(20 "In9.Cu" signal "IN3")
		(22 "In10.Cu" signal "GND4")
		(24 "In11.Cu" signal "IN4")
		(26 "In12.Cu" signal "GND5")
		(28 "In13.Cu" signal "IN5")
		(30 "In14.Cu" signal "GND6")
		(32 "In15.Cu" signal "IN6")
		(34 "In16.Cu" signal "GND7")
		(2 "B.Cu" signal "BOTTOM")
		(9 "F.Adhes" user "F.Adhesive")
		(11 "B.Adhes" user "B.Adhesive")
		(13 "F.Paste" user "Package Geometry/Pastemask Top")
		(15 "B.Paste" user "Package Geometry/Pastemask Bottom")
		(5 "F.SilkS" user "Ref Des/Silkscreen Top")
		(7 "B.SilkS" user "Ref Des/Silkscreen Bottom")
		(1 "F.Mask" user "Board Geometry/Soldermask Top")
		(3 "B.Mask" user "Board Geometry/Soldermask Bottom")
		(17 "Dwgs.User" user "User.Drawings")
		(19 "Cmts.User" user "User.Comments")
		(21 "Eco1.User" user "User.Eco1")
		(23 "Eco2.User" user "User.Eco2")
		(25 "Edge.Cuts" user "Board Geometry/Outline")
		(27 "Margin" user)
		(31 "F.CrtYd" user "Package Geometry/Place Bound Top")
		(29 "B.CrtYd" user "Package Geometry/Place Bound Bottom")
		(35 "F.Fab" user "Ref Des/Assembly Top")
		(33 "B.Fab" user "Ref Des/Assembly Bottom")
	)
	(footprint ""
		(layer "F.Cu")
		(at 129.306066 -134.434326)
		(property "Reference" "PC328"
			(at 0 0 0)
			(layer "F.SilkS")
			(hide yes)
			(effects
				(font
					(size 1.27 1.27)
				)
			)
		)
		(property "Value" ""
			(at 0 0 0)
			(layer "F.Fab")
			(effects
				(font
					(size 1.27 1.27)
				)
			)
		)
		(duplicate_pad_numbers_are_jumpers no)
		(fp_line
			(start -0.7874 -0.4064)
			(end 0.7874 -0.4064)
			(stroke
				(width 0.1524)
				(type default)
			)
			(layer "F.SilkS")
		)
		(fp_line
			(start -0.7874 0.4064)
			(end -0.7874 -0.4064)
			(stroke
				(width 0.1524)
				(type default)
			)
			(layer "F.SilkS")
		)
		(fp_line
			(start 0.7874 -0.4064)
			(end 0.7874 0.4064)
			(stroke
				(width 0.1524)
				(type default)
			)
			(layer "F.SilkS")
		)
		(fp_line
			(start 0.7874 0.4064)
			(end -0.7874 0.4064)
			(stroke
				(width 0.1524)
				(type default)
			)
			(layer "F.SilkS")
		)
		(fp_line
			(start -0.67945 -0.305054)
			(end -0.12065 -0.305054)
			(stroke
				(width 0.1)
				(type default)
			)
			(layer "F.Fab")
		)
		(fp_line
			(start -0.67945 0.3048)
			(end -0.67945 -0.305054)
			(stroke
				(width 0.1)
				(type default)
			)
			(layer "F.Fab")
		)
		(fp_line
			(start -0.12065 -0.305054)
			(end -0.12065 -0.2794)
			(stroke
				(width 0.1)
				(type default)
			)
			(layer "F.Fab")
		)
		(fp_line
			(start -0.12065 -0.2794)
			(end 0.12065 -0.2794)
			(stroke
				(width 0.1)
				(type default)
			)
			(layer "F.Fab")
		)
		(fp_line
			(start -0.12065 0.2794)
			(end -0.12065 0.3048)
			(stroke
				(width 0.1)
				(type default)
			)
			(layer "F.Fab")
		)
		(fp_line
			(start -0.12065 0.3048)
			(end -0.67945 0.3048)
			(stroke
				(width 0.1)
				(type default)
			)
			(layer "F.Fab")
		)
		(fp_line
			(start 0.120396 0.2794)
			(end -0.12065 0.2794)
			(stroke
				(width 0.1)
				(type default)
			)
			(layer "F.Fab")
		)
		(fp_line
			(start 0.120396 0.3048)
			(end 0.120396 0.2794)
			(stroke
				(width 0.1)
				(type default)
			)
			(layer "F.Fab")
		)
		(fp_line
			(start 0.12065 -0.3048)
			(end 0.67945 -0.3048)
			(stroke
				(width 0.1)
				(type default)
			)
			(layer "F.Fab")
		)
		(fp_line
			(start 0.12065 -0.2794)
			(end 0.12065 -0.3048)
			(stroke
				(width 0.1)
				(type default)
			)
			(layer "F.Fab")
		)
		(fp_line
			(start 0.67945 -0.3048)
			(end 0.67945 0.3048)
			(stroke
				(width 0.1)
				(type default)
			)
			(layer "F.Fab")
		)
		(fp_line
			(start 0.67945 0.3048)
			(end 0.120396 0.3048)
			(stroke
				(width 0.1)
				(type default)
			)
			(layer "F.Fab")
		)
		(pad "1" smd circle
			(at -0.40005 0)
			(size 0 0)
			(layers "F.Cu" "F.Mask" "F.Paste")
			(net "P12V_AUX")
		)
		(pad "2" smd circle
			(at 0.40005 0)
			(size 0 0)
			(layers "F.Cu" "F.Mask" "F.Paste")
			(net "GND")
		)
	)
	(footprint ""
		(layer "F.Cu")
		(at 16.252952 -159.173418 90)
		(property "Reference" "PC598"
			(at 0 0 90)
			(layer "F.SilkS")
			(hide yes)
			(effects
				(font
					(size 1.27 1.27)
				)
			)
		)
		(property "Value" ""
			(at 0 0 90)
			(layer "F.Fab")
			(effects
				(font
					(size 1.27 1.27)
				)
			)
		)
		(duplicate_pad_numbers_are_jumpers no)
		(fp_line
			(start 0.7874 -0.4064)
			(end 0.7874 0.4064)
			(stroke
				(width 0.1524)
				(type default)
			)
			(layer "F.SilkS")
		)
		(fp_line
			(start -0.7874 -0.4064)
			(end 0.7874 -0.4064)
			(stroke
				(width 0.1524)
				(type default)
			)
			(layer "F.SilkS")
		)
		(fp_line
			(start 0.7874 0.4064)
			(end -0.7874 0.4064)
			(stroke
				(width 0.1524)
				(type default)
			)
			(layer "F.SilkS")
		)
		(fp_line
			(start -0.7874 0.4064)
			(end -0.7874 -0.4064)
			(stroke
				(width 0.1524)
				(type default)
			)
			(layer "F.SilkS")
		)
		(fp_line
			(start -0.12065 -0.305054)
			(end -0.12065 -0.2794)
			(stroke
				(width 0.1)
				(type default)
			)
			(layer "F.Fab")
		)
		(fp_line
			(start -0.67945 -0.305054)
			(end -0.12065 -0.305054)
			(stroke
				(width 0.1)
				(type default)
			)
			(layer "F.Fab")
		)
		(fp_line
			(start 0.67945 -0.3048)
			(end 0.67945 0.3048)
			(stroke
				(width 0.1)
				(type default)
			)
			(layer "F.Fab")
		)
		(fp_line
			(start 0.12065 -0.3048)
			(end 0.67945 -0.3048)
			(stroke
				(width 0.1)
				(type default)
			)
			(layer "F.Fab")
		)
		(fp_line
			(start 0.12065 -0.2794)
			(end 0.12065 -0.3048)
			(stroke
				(width 0.1)
				(type default)
			)
			(layer "F.Fab")
		)
		(fp_line
			(start -0.12065 -0.2794)
			(end 0.12065 -0.2794)
			(stroke
				(width 0.1)
				(type default)
			)
			(layer "F.Fab")
		)
		(fp_line
			(start 0.120396 0.2794)
			(end -0.12065 0.2794)
			(stroke
				(width 0.1)
				(type default)
			)
			(layer "F.Fab")
		)
		(fp_line
			(start -0.12065 0.2794)
			(end -0.12065 0.3048)
			(stroke
				(width 0.1)
				(type default)
			)
			(layer "F.Fab")
		)
		(fp_line
			(start 0.67945 0.3048)
			(end 0.120396 0.3048)
			(stroke
				(width 0.1)
				(type default)
			)
			(layer "F.Fab")
		)
		(fp_line
			(start 0.120396 0.3048)
			(end 0.120396 0.2794)
			(stroke
				(width 0.1)
				(type default)
			)
			(layer "F.Fab")
		)
		(fp_line
			(start -0.12065 0.3048)
			(end -0.67945 0.3048)
			(stroke
				(width 0.1)
				(type default)
			)
			(layer "F.Fab")
		)
		(fp_line
			(start -0.67945 0.3048)
			(end -0.67945 -0.305054)
			(stroke
				(width 0.1)
				(type default)
			)
			(layer "F.Fab")
		)
		(pad "1" smd circle
			(at -0.40005 0 90)
			(size 0 0)
			(layers "F.Cu" "F.Mask" "F.Paste")
			(net "P12V_AUX")
		)
		(pad "2" smd circle
			(at 0.40005 0 90)
			(size 0 0)
			(layers "F.Cu" "F.Mask" "F.Paste")
			(net "GND")
		)
	)
	(footprint ""
		(layer "F.Cu")
		(at 26.243788 -44.87291)
		(property "Reference" "R507"
			(at 0 0 0)
			(layer "F.SilkS")
			(hide yes)
			(effects
				(font
					(size 1.27 1.27)
				)
			)
		)
		(property "Value" ""
			(at 0 0 0)
			(layer "F.Fab")
			(effects
				(font
					(size 1.27 1.27)
				)
			)
		)
		(duplicate_pad_numbers_are_jumpers no)
		(fp_line
			(start -0.7874 -0.4064)
			(end 0.7874 -0.4064)
			(stroke
				(width 0.1524)
				(type default)
			)
			(layer "F.SilkS")
		)
		(fp_line
			(start -0.7874 0.4064)
			(end -0.7874 -0.4064)
			(stroke
				(width 0.1524)
				(type default)
			)
			(layer "F.SilkS")
		)
		(fp_line
			(start 0.7874 -0.4064)
			(end 0.7874 0.4064)
			(stroke
				(width 0.1524)
				(type default)
			)
			(layer "F.SilkS")
		)
		(fp_line
			(start 0.7874 0.4064)
			(end -0.7874 0.4064)
			(stroke
				(width 0.1524)
				(type default)
			)
			(layer "F.SilkS")
		)
		(fp_line
			(start -0.67945 -0.305054)
			(end -0.12065 -0.305054)
			(stroke
				(width 0.1)
				(type default)
			)
			(layer "F.Fab")
		)
		(fp_line
			(start -0.67945 0.3048)
			(end -0.67945 -0.305054)
			(stroke
				(width 0.1)
				(type default)
			)
			(layer "F.Fab")
		)
		(fp_line
			(start -0.12065 -0.305054)
			(end -0.12065 -0.2794)
			(stroke
				(width 0.1)
				(type default)
			)
			(layer "F.Fab")
		)
		(fp_line
			(start -0.12065 -0.2794)
			(end 0.12065 -0.2794)
			(stroke
				(width 0.1)
				(type default)
			)
			(layer "F.Fab")
		)
		(fp_line
			(start -0.12065 0.2794)
			(end -0.12065 0.3048)
			(stroke
				(width 0.1)
				(type default)
			)
			(layer "F.Fab")
		)
		(fp_line
			(start -0.12065 0.3048)
			(end -0.67945 0.3048)
			(stroke
				(width 0.1)
				(type default)
			)
			(layer "F.Fab")
		)
		(fp_line
			(start 0.120396 0.2794)
			(end -0.12065 0.2794)
			(stroke
				(width 0.1)
				(type default)
			)
			(layer "F.Fab")
		)
		(fp_line
			(start 0.120396 0.3048)
			(end 0.120396 0.2794)
			(stroke
				(width 0.1)
				(type default)
			)
			(layer "F.Fab")
		)
		(fp_line
			(start 0.12065 -0.3048)
			(end 0.67945 -0.3048)
			(stroke
				(width 0.1)
				(type default)
			)
			(layer "F.Fab")
		)
		(fp_line
			(start 0.12065 -0.2794)
			(end 0.12065 -0.3048)
			(stroke
				(width 0.1)
				(type default)
			)
			(layer "F.Fab")
		)
		(fp_line
			(start 0.67945 -0.3048)
			(end 0.67945 0.3048)
			(stroke
				(width 0.1)
				(type default)
			)
			(layer "F.Fab")
		)
		(fp_line
			(start 0.67945 0.3048)
			(end 0.120396 0.3048)
			(stroke
				(width 0.1)
				(type default)
			)
			(layer "F.Fab")
		)
		(pad "1" smd circle
			(at -0.40005 0)
			(size 0 0)
			(layers "F.Cu" "F.Mask" "F.Paste")
			(net "SSD0_ADC_A0")
		)
		(pad "2" smd circle
			(at 0.40005 0)
			(size 0 0)
			(layers "F.Cu" "F.Mask" "F.Paste")
			(net "P3V3_AUX")
		)
	)
)
